# SCM (Grand Teton) — schematic netlist excerpt (pin names and nets, part order shuffled) for the footprints in the layout excerpt that follows; sources: Cadence DE-HDL packaged netlist, KiCad conversion of 12092022_DA0F0TMDCD0_F0T_Management_Board_D_brd_V3_OCP.brd

C224  Q_CAP  10UF 6.3V 20% X6S  pkg C0402  page 17 : A = PGPPA_BMC_AUX ; B = GND
R26  Q_RES  10 1% CHIP  pkg 0402LF  page 15 : A = V_DACR_R ; B = V_DACR

(kicad_pcb
	(version 20260206)
	(generator "pcbnew")
	(generator_version "10.0")
	(general
		(thickness 1.6)
		(legacy_teardrops no)
	)
	(paper "A4")
	(title_block
		(title "12092022_DA0F0TMDCD0_F0T_Management_Board_D_brd_V3_OCP.brd")
		(comment 1 "Grand Teton / footprints 3-4 of 1440")
	)
	(layers
		(0 "F.Cu" signal "TOP")
		(4 "In1.Cu" signal "GND")
		(6 "In2.Cu" signal "IN1")
		(8 "In3.Cu" signal "GND1")
		(10 "In4.Cu" signal "IN2")
		(12 "In5.Cu" signal "VCC")
		(14 "In6.Cu" signal "VCC1")
		(16 "In7.Cu" signal "IN3")
		(18 "In8.Cu" signal "GND2")
		(20 "In9.Cu" signal "IN4")
		(22 "In10.Cu" signal "GND3")
		(2 "B.Cu" signal "BOTTOM")
		(9 "F.Adhes" user "F.Adhesive")
		(11 "B.Adhes" user "B.Adhesive")
		(13 "F.Paste" user "Package Geometry/Pastemask Top")
		(15 "B.Paste" user "Package Geometry/Pastemask Bottom")
		(5 "F.SilkS" user "Ref Des/Silkscreen Top")
		(7 "B.SilkS" user "Ref Des/Silkscreen Bottom")
		(1 "F.Mask" user "Board Geometry/Soldermask Top")
		(3 "B.Mask" user "Board Geometry/Soldermask Bottom")
		(17 "Dwgs.User" user "User.Drawings")
		(19 "Cmts.User" user "User.Comments")
		(21 "Eco1.User" user "User.Eco1")
		(23 "Eco2.User" user "User.Eco2")
		(25 "Edge.Cuts" user "Board Geometry/Outline")
		(27 "Margin" user)
		(31 "F.CrtYd" user "Package Geometry/Place Bound Top")
		(29 "B.CrtYd" user "Package Geometry/Place Bound Bottom")
		(35 "F.Fab" user "Ref Des/Assembly Top")
		(33 "B.Fab" user "Ref Des/Assembly Bottom")
	)
	(footprint ""
		(layer "F.Cu")
		(at 46.5709 -66.23812 90)
		(property "Reference" "R26"
			(at 0 0 90)
			(layer "F.SilkS")
			(hide yes)
			(effects
				(font
					(size 1.27 1.27)
				)
			)
		)
		(property "Value" ""
			(at 0 0 90)
			(layer "F.Fab")
			(effects
				(font
					(size 1.27 1.27)
				)
			)
		)
		(duplicate_pad_numbers_are_jumpers no)
		(fp_line
			(start 0.7874 -0.4064)
			(end 0.7874 0.4064)
			(stroke
				(width 0.1524)
				(type default)
			)
			(layer "F.SilkS")
		)
		(fp_line
			(start -0.7874 -0.4064)
			(end 0.7874 -0.4064)
			(stroke
				(width 0.1524)
				(type default)
			)
			(layer "F.SilkS")
		)
		(fp_line
			(start 0.7874 0.4064)
			(end -0.7874 0.4064)
			(stroke
				(width 0.1524)
				(type default)
			)
			(layer "F.SilkS")
		)
		(fp_line
			(start -0.7874 0.4064)
			(end -0.7874 -0.4064)
			(stroke
				(width 0.1524)
				(type default)
			)
			(layer "F.SilkS")
		)
		(fp_line
			(start -0.12065 -0.305054)
			(end -0.12065 -0.2794)
			(stroke
				(width 0.1)
				(type default)
			)
			(layer "F.Fab")
		)
		(fp_line
			(start -0.67945 -0.305054)
			(end -0.12065 -0.305054)
			(stroke
				(width 0.1)
				(type default)
			)
			(layer "F.Fab")
		)
		(fp_line
			(start 0.67945 -0.3048)
			(end 0.67945 0.3048)
			(stroke
				(width 0.1)
				(type default)
			)
			(layer "F.Fab")
		)
		(fp_line
			(start 0.12065 -0.3048)
			(end 0.67945 -0.3048)
			(stroke
				(width 0.1)
				(type default)
			)
			(layer "F.Fab")
		)
		(fp_line
			(start 0.12065 -0.2794)
			(end 0.12065 -0.3048)
			(stroke
				(width 0.1)
				(type default)
			)
			(layer "F.Fab")
		)
		(fp_line
			(start -0.12065 -0.2794)
			(end 0.12065 -0.2794)
			(stroke
				(width 0.1)
				(type default)
			)
			(layer "F.Fab")
		)
		(fp_line
			(start 0.120396 0.2794)
			(end -0.12065 0.2794)
			(stroke
				(width 0.1)
				(type default)
			)
			(layer "F.Fab")
		)
		(fp_line
			(start -0.12065 0.2794)
			(end -0.12065 0.3048)
			(stroke
				(width 0.1)
				(type default)
			)
			(layer "F.Fab")
		)
		(fp_line
			(start 0.67945 0.3048)
			(end 0.120396 0.3048)
			(stroke
				(width 0.1)
				(type default)
			)
			(layer "F.Fab")
		)
		(fp_line
			(start 0.120396 0.3048)
			(end 0.120396 0.2794)
			(stroke
				(width 0.1)
				(type default)
			)
			(layer "F.Fab")
		)
		(fp_line
			(start -0.12065 0.3048)
			(end -0.67945 0.3048)
			(stroke
				(width 0.1)
				(type default)
			)
			(layer "F.Fab")
		)
		(fp_line
			(start -0.67945 0.3048)
			(end -0.67945 -0.305054)
			(stroke
				(width 0.1)
				(type default)
			)
			(layer "F.Fab")
		)
		(pad "1" smd circle
			(at -0.40005 0 90)
			(size 0 0)
			(layers "F.Cu" "F.Mask" "F.Paste")
			(net "V_DACR_R")
		)
		(pad "2" smd circle
			(at 0.40005 0 90)
			(size 0 0)
			(layers "F.Cu" "F.Mask" "F.Paste")
			(net "V_DACR")
		)
	)
	(footprint ""
		(layer "F.Cu")
		(at 63.960502 -68.174362)
		(property "Reference" "C224"
			(at 0 0 0)
			(layer "F.SilkS")
			(hide yes)
			(effects
				(font
					(size 1.27 1.27)
				)
			)
		)
		(property "Value" ""
			(at 0 0 0)
			(layer "F.Fab")
			(effects
				(font
					(size 1.27 1.27)
				)
			)
		)
		(duplicate_pad_numbers_are_jumpers no)
		(fp_line
			(start -0.7874 -0.4064)
			(end 0.7874 -0.4064)
			(stroke
				(width 0.1524)
				(type default)
			)
			(layer "F.SilkS")
		)
		(fp_line
			(start -0.7874 0.4064)
			(end -0.7874 -0.4064)
			(stroke
				(width 0.1524)
				(type default)
			)
			(layer "F.SilkS")
		)
		(fp_line
			(start 0.7874 -0.4064)
			(end 0.7874 0.4064)
			(stroke
				(width 0.1524)
				(type default)
			)
			(layer "F.SilkS")
		)
		(fp_line
			(start 0.7874 0.4064)
			(end -0.7874 0.4064)
			(stroke
				(width 0.1524)
				(type default)
			)
			(layer "F.SilkS")
		)
		(fp_line
			(start -0.67945 -0.305054)
			(end -0.12065 -0.305054)
			(stroke
				(width 0.1)
				(type default)
			)
			(layer "F.Fab")
		)
		(fp_line
			(start -0.67945 0.3048)
			(end -0.67945 -0.305054)
			(stroke
				(width 0.1)
				(type default)
			)
			(layer "F.Fab")
		)
		(fp_line
			(start -0.12065 -0.305054)
			(end -0.12065 -0.2794)
			(stroke
				(width 0.1)
				(type default)
			)
			(layer "F.Fab")
		)
		(fp_line
			(start -0.12065 -0.2794)
			(end 0.12065 -0.2794)
			(stroke
				(width 0.1)
				(type default)
			)
			(layer "F.Fab")
		)
		(fp_line
			(start -0.12065 0.2794)
			(end -0.12065 0.3048)
			(stroke
				(width 0.1)
				(type default)
			)
			(layer "F.Fab")
		)
		(fp_line
			(start -0.12065 0.3048)
			(end -0.67945 0.3048)
			(stroke
				(width 0.1)
				(type default)
			)
			(layer "F.Fab")
		)
		(fp_line
			(start 0.120396 0.2794)
			(end -0.12065 0.2794)
			(stroke
				(width 0.1)
				(type default)
			)
			(layer "F.Fab")
		)
		(fp_line
			(start 0.120396 0.3048)
			(end 0.120396 0.2794)
			(stroke
				(width 0.1)
				(type default)
			)
			(layer "F.Fab")
		)
		(fp_line
			(start 0.12065 -0.3048)
			(end 0.67945 -0.3048)
			(stroke
				(width 0.1)
				(type default)
			)
			(layer "F.Fab")
		)
		(fp_line
			(start 0.12065 -0.2794)
			(end 0.12065 -0.3048)
			(stroke
				(width 0.1)
				(type default)
			)
			(layer "F.Fab")
		)
		(fp_line
			(start 0.67945 -0.3048)
			(end 0.67945 0.3048)
			(stroke
				(width 0.1)
				(type default)
			)
			(layer "F.Fab")
		)
		(fp_line
			(start 0.67945 0.3048)
			(end 0.120396 0.3048)
			(stroke
				(width 0.1)
				(type default)
			)
			(layer "F.Fab")
		)
		(pad "1" smd circle
			(at -0.40005 0)
			(size 0 0)
			(layers "F.Cu" "F.Mask" "F.Paste")
			(net "PGPPA_BMC_AUX")
		)
		(pad "2" smd circle
			(at 0.40005 0)
			(size 0 0)
			(layers "F.Cu" "F.Mask" "F.Paste")
			(net "GND")
		)
	)
)
